(kicad_pcb
	(version 20260206)
	(generator "pcbnew")
	(generator_version "10.0")
	(general
		(thickness 1.6)
		(legacy_teardrops no)
	)
	(paper "A4")
	(title_block
		(title "01162023_DA0F0TEBIF0_F0T_Expander_BD_F_brd_V02_OCP.brd")
		(comment 1 "Grand Teton / footprints 2657-2662 of 9728")
	)
	(layers
		(0 "F.Cu" signal "TOP")
		(4 "In1.Cu" signal "GND")
		(6 "In2.Cu" signal "VCC")
		(8 "In3.Cu" signal "VCC1")
		(10 "In4.Cu" signal "GND1")
		(12 "In5.Cu" signal "IN1")
		(14 "In6.Cu" signal "GND2")
		(16 "In7.Cu" signal "IN2")
		(18 "In8.Cu" signal "GND3")
		(20 "In9.Cu" signal "IN3")
		(22 "In10.Cu" signal "GND4")
		(24 "In11.Cu" signal "IN4")
		(26 "In12.Cu" signal "GND5")
		(28 "In13.Cu" signal "IN5")
		(30 "In14.Cu" signal "GND6")
		(32 "In15.Cu" signal "IN6")
		(34 "In16.Cu" signal "GND7")
		(2 "B.Cu" signal "BOTTOM")
		(9 "F.Adhes" user "F.Adhesive")
		(11 "B.Adhes" user "B.Adhesive")
		(13 "F.Paste" user "Package Geometry/Pastemask Top")
		(15 "B.Paste" user "Package Geometry/Pastemask Bottom")
		(5 "F.SilkS" user "Ref Des/Silkscreen Top")
		(7 "B.SilkS" user "Ref Des/Silkscreen Bottom")
		(1 "F.Mask" user "Board Geometry/Soldermask Top")
		(3 "B.Mask" user "Board Geometry/Soldermask Bottom")
		(17 "Dwgs.User" user "User.Drawings")
		(19 "Cmts.User" user "User.Comments")
		(21 "Eco1.User" user "User.Eco1")
		(23 "Eco2.User" user "User.Eco2")
		(25 "Edge.Cuts" user "Board Geometry/Outline")
		(27 "Margin" user)
		(31 "F.CrtYd" user "Package Geometry/Place Bound Top")
		(29 "B.CrtYd" user "Package Geometry/Place Bound Bottom")
		(35 "F.Fab" user "Ref Des/Assembly Top")
		(33 "B.Fab" user "Ref Des/Assembly Bottom")
	)
	(footprint ""
		(layer "F.Cu")
		(at 377.722384 -252.356874 -90)
		(property "Reference" "R1428"
			(at 0 0 270)
			(layer "F.SilkS")
			(hide yes)
			(effects
				(font
					(size 1.27 1.27)
				)
			)
		)
		(property "Value" ""
			(at 0 0 270)
			(layer "F.Fab")
			(effects
				(font
					(size 1.27 1.27)
				)
			)
		)
		(duplicate_pad_numbers_are_jumpers no)
		(fp_line
			(start -0.7874 0.4064)
			(end -0.7874 -0.4064)
			(stroke
				(width 0.1524)
				(type default)
			)
			(layer "F.SilkS")
		)
		(fp_line
			(start 0.7874 0.4064)
			(end -0.7874 0.4064)
			(stroke
				(width 0.1524)
				(type default)
			)
			(layer "F.SilkS")
		)
		(fp_line
			(start -0.7874 -0.4064)
			(end 0.7874 -0.4064)
			(stroke
				(width 0.1524)
				(type default)
			)
			(layer "F.SilkS")
		)
		(fp_line
			(start 0.7874 -0.4064)
			(end 0.7874 0.4064)
			(stroke
				(width 0.1524)
				(type default)
			)
			(layer "F.SilkS")
		)
		(fp_line
			(start -0.67945 0.3048)
			(end -0.67945 -0.305054)
			(stroke
				(width 0.1)
				(type default)
			)
			(layer "F.Fab")
		)
		(fp_line
			(start -0.12065 0.3048)
			(end -0.67945 0.3048)
			(stroke
				(width 0.1)
				(type default)
			)
			(layer "F.Fab")
		)
		(fp_line
			(start 0.120396 0.3048)
			(end 0.120396 0.2794)
			(stroke
				(width 0.1)
				(type default)
			)
			(layer "F.Fab")
		)
		(fp_line
			(start 0.67945 0.3048)
			(end 0.120396 0.3048)
			(stroke
				(width 0.1)
				(type default)
			)
			(layer "F.Fab")
		)
		(fp_line
			(start -0.12065 0.2794)
			(end -0.12065 0.3048)
			(stroke
				(width 0.1)
				(type default)
			)
			(layer "F.Fab")
		)
		(fp_line
			(start 0.120396 0.2794)
			(end -0.12065 0.2794)
			(stroke
				(width 0.1)
				(type default)
			)
			(layer "F.Fab")
		)
		(fp_line
			(start -0.12065 -0.2794)
			(end 0.12065 -0.2794)
			(stroke
				(width 0.1)
				(type default)
			)
			(layer "F.Fab")
		)
		(fp_line
			(start 0.12065 -0.2794)
			(end 0.12065 -0.3048)
			(stroke
				(width 0.1)
				(type default)
			)
			(layer "F.Fab")
		)
		(fp_line
			(start 0.12065 -0.3048)
			(end 0.67945 -0.3048)
			(stroke
				(width 0.1)
				(type default)
			)
			(layer "F.Fab")
		)
		(fp_line
			(start 0.67945 -0.3048)
			(end 0.67945 0.3048)
			(stroke
				(width 0.1)
				(type default)
			)
			(layer "F.Fab")
		)
		(fp_line
			(start -0.67945 -0.305054)
			(end -0.12065 -0.305054)
			(stroke
				(width 0.1)
				(type default)
			)
			(layer "F.Fab")
		)
		(fp_line
			(start -0.12065 -0.305054)
			(end -0.12065 -0.2794)
			(stroke
				(width 0.1)
				(type default)
			)
			(layer "F.Fab")
		)
		(pad "1" smd circle
			(at -0.40005 0 270)
			(size 0 0)
			(layers "F.Cu" "F.Mask" "F.Paste")
			(net "GND")
		)
		(pad "2" smd circle
			(at 0.40005 0 270)
			(size 0 0)
			(layers "F.Cu" "F.Mask" "F.Paste")
			(net "PEX3_MODE_SEL3")
		)
	)
	(footprint ""
		(layer "F.Cu")
		(at 41.20134 -55.78475 -90)
		(property "Reference" "PD26"
			(at 1.83515 2.23647 90)
			(unlocked yes)
			(layer "F.SilkS")
			(effects
				(font
					(size 0.7874 0.5842)
					(thickness 0.1524)
				)
				(justify left)
			)
		)
		(property "Value" ""
			(at 0 0 270)
			(layer "F.Fab")
			(effects
				(font
					(size 1.27 1.27)
				)
			)
		)
		(duplicate_pad_numbers_are_jumpers no)
		(fp_line
			(start -3.400044 1.459992)
			(end -3.400044 -1.459992)
			(stroke
				(width 0.1524)
				(type default)
			)
			(layer "F.SilkS")
		)
		(fp_line
			(start 4.107942 1.459992)
			(end -3.400044 1.459992)
			(stroke
				(width 0.1524)
				(type default)
			)
			(layer "F.SilkS")
		)
		(fp_line
			(start -3.400044 -1.459992)
			(end 4.107942 -1.459992)
			(stroke
				(width 0.1524)
				(type default)
			)
			(layer "F.SilkS")
		)
		(fp_line
			(start 4.107942 -1.459992)
			(end 4.107942 1.459992)
			(stroke
				(width 0.1524)
				(type default)
			)
			(layer "F.SilkS")
		)
		(fp_poly
			(pts
				(xy 4.107942 -1.459992) (xy 4.107942 1.459992) (xy 3.308096 1.459992) (xy 3.308096 -1.459992)
			)
			(stroke
				(width 0)
				(type default)
			)
			(fill yes)
			(layer "F.SilkS")
		)
		(fp_line
			(start -2.29997 1.459992)
			(end -2.29997 -1.459992)
			(stroke
				(width 0.1)
				(type default)
			)
			(layer "F.Fab")
		)
		(fp_line
			(start 2.29997 1.459992)
			(end -2.29997 1.459992)
			(stroke
				(width 0.1)
				(type default)
			)
			(layer "F.Fab")
		)
		(fp_line
			(start -2.29997 -1.459992)
			(end 2.29997 -1.459992)
			(stroke
				(width 0.1)
				(type default)
			)
			(layer "F.Fab")
		)
		(fp_line
			(start 2.29997 -1.459992)
			(end 2.29997 1.459992)
			(stroke
				(width 0.1)
				(type default)
			)
			(layer "F.Fab")
		)
		(fp_text user "-"
			(at 5.4102 0.29845 90)
			(unlocked yes)
			(layer "F.SilkS")
			(effects
				(font
					(size 1.905 1.4224)
					(thickness 0.1524)
				)
				(justify left)
			)
		)
		(fp_text user "+"
			(at -4.7752 -0.12065 270)
			(unlocked yes)
			(layer "F.SilkS")
			(effects
				(font
					(size 1.905 1.4224)
					(thickness 0.1524)
				)
				(justify left)
			)
		)
		(fp_text user "-"
			(at 5.4102 0.29845 90)
			(unlocked yes)
			(layer "F.Fab")
			(effects
				(font
					(size 1.905 1.4224)
					(thickness 0.1524)
				)
				(justify left)
			)
		)
		(fp_text user "+"
			(at -4.7752 -0.12065 270)
			(unlocked yes)
			(layer "F.Fab")
			(effects
				(font
					(size 1.905 1.4224)
					(thickness 0.1524)
				)
				(justify left)
			)
		)
		(pad "A" smd rect
			(at -1.999996 0)
			(size 1.7018 2.5146)
			(layers "F.Cu" "F.Mask" "F.Paste")
			(net "GND")
		)
		(pad "C" smd rect
			(at 1.999996 0)
			(size 1.7018 2.5146)
			(layers "F.Cu" "F.Mask" "F.Paste")
			(net "P12V_SSD1_R")
		)
	)
	(footprint ""
		(layer "F.Cu")
		(at 277.717504 -395.162532 90)
		(property "Reference" "R1803"
			(at 0 0 90)
			(layer "F.SilkS")
			(hide yes)
			(effects
				(font
					(size 1.27 1.27)
				)
			)
		)
		(property "Value" ""
			(at 0 0 90)
			(layer "F.Fab")
			(effects
				(font
					(size 1.27 1.27)
				)
			)
		)
		(duplicate_pad_numbers_are_jumpers no)
		(fp_line
			(start 0.7874 -0.4064)
			(end 0.7874 0.4064)
			(stroke
				(width 0.1524)
				(type default)
			)
			(layer "F.SilkS")
		)
		(fp_line
			(start -0.7874 -0.4064)
			(end 0.7874 -0.4064)
			(stroke
				(width 0.1524)
				(type default)
			)
			(layer "F.SilkS")
		)
		(fp_line
			(start 0.7874 0.4064)
			(end -0.7874 0.4064)
			(stroke
				(width 0.1524)
				(type default)
			)
			(layer "F.SilkS")
		)
		(fp_line
			(start -0.7874 0.4064)
			(end -0.7874 -0.4064)
			(stroke
				(width 0.1524)
				(type default)
			)
			(layer "F.SilkS")
		)
		(fp_line
			(start -0.12065 -0.305054)
			(end -0.12065 -0.2794)
			(stroke
				(width 0.1)
				(type default)
			)
			(layer "F.Fab")
		)
		(fp_line
			(start -0.67945 -0.305054)
			(end -0.12065 -0.305054)
			(stroke
				(width 0.1)
				(type default)
			)
			(layer "F.Fab")
		)
		(fp_line
			(start 0.67945 -0.3048)
			(end 0.67945 0.3048)
			(stroke
				(width 0.1)
				(type default)
			)
			(layer "F.Fab")
		)
		(fp_line
			(start 0.12065 -0.3048)
			(end 0.67945 -0.3048)
			(stroke
				(width 0.1)
				(type default)
			)
			(layer "F.Fab")
		)
		(fp_line
			(start 0.12065 -0.2794)
			(end 0.12065 -0.3048)
			(stroke
				(width 0.1)
				(type default)
			)
			(layer "F.Fab")
		)
		(fp_line
			(start -0.12065 -0.2794)
			(end 0.12065 -0.2794)
			(stroke
				(width 0.1)
				(type default)
			)
			(layer "F.Fab")
		)
		(fp_line
			(start 0.120396 0.2794)
			(end -0.12065 0.2794)
			(stroke
				(width 0.1)
				(type default)
			)
			(layer "F.Fab")
		)
		(fp_line
			(start -0.12065 0.2794)
			(end -0.12065 0.3048)
			(stroke
				(width 0.1)
				(type default)
			)
			(layer "F.Fab")
		)
		(fp_line
			(start 0.67945 0.3048)
			(end 0.120396 0.3048)
			(stroke
				(width 0.1)
				(type default)
			)
			(layer "F.Fab")
		)
		(fp_line
			(start 0.120396 0.3048)
			(end 0.120396 0.2794)
			(stroke
				(width 0.1)
				(type default)
			)
			(layer "F.Fab")
		)
		(fp_line
			(start -0.12065 0.3048)
			(end -0.67945 0.3048)
			(stroke
				(width 0.1)
				(type default)
			)
			(layer "F.Fab")
		)
		(fp_line
			(start -0.67945 0.3048)
			(end -0.67945 -0.305054)
			(stroke
				(width 0.1)
				(type default)
			)
			(layer "F.Fab")
		)
		(pad "1" smd circle
			(at -0.40005 0 90)
			(size 0 0)
			(layers "F.Cu" "F.Mask" "F.Paste")
			(net "P3V3_AUX")
		)
		(pad "2" smd circle
			(at 0.40005 0 90)
			(size 0 0)
			(layers "F.Cu" "F.Mask" "F.Paste")
			(net "MB_BMC_MON")
		)
	)
	(footprint ""
		(layer "F.Cu")
		(at 318.89319 -304.90795 -90)
		(property "Reference" "R6809"
			(at 0 0 270)
			(layer "F.SilkS")
			(hide yes)
			(effects
				(font
					(size 1.27 1.27)
				)
			)
		)
		(property "Value" ""
			(at 0 0 270)
			(layer "F.Fab")
			(effects
				(font
					(size 1.27 1.27)
				)
			)
		)
		(duplicate_pad_numbers_are_jumpers no)
		(fp_line
			(start -0.7874 0.4064)
			(end -0.7874 -0.4064)
			(stroke
				(width 0.1524)
				(type default)
			)
			(layer "F.SilkS")
		)
		(fp_line
			(start 0.7874 0.4064)
			(end -0.7874 0.4064)
			(stroke
				(width 0.1524)
				(type default)
			)
			(layer "F.SilkS")
		)
		(fp_line
			(start -0.7874 -0.4064)
			(end 0.7874 -0.4064)
			(stroke
				(width 0.1524)
				(type default)
			)
			(layer "F.SilkS")
		)
		(fp_line
			(start 0.7874 -0.4064)
			(end 0.7874 0.4064)
			(stroke
				(width 0.1524)
				(type default)
			)
			(layer "F.SilkS")
		)
		(fp_line
			(start -0.67945 0.3048)
			(end -0.67945 -0.305054)
			(stroke
				(width 0.1)
				(type default)
			)
			(layer "F.Fab")
		)
		(fp_line
			(start -0.12065 0.3048)
			(end -0.67945 0.3048)
			(stroke
				(width 0.1)
				(type default)
			)
			(layer "F.Fab")
		)
		(fp_line
			(start 0.120396 0.3048)
			(end 0.120396 0.2794)
			(stroke
				(width 0.1)
				(type default)
			)
			(layer "F.Fab")
		)
		(fp_line
			(start 0.67945 0.3048)
			(end 0.120396 0.3048)
			(stroke
				(width 0.1)
				(type default)
			)
			(layer "F.Fab")
		)
		(fp_line
			(start -0.12065 0.2794)
			(end -0.12065 0.3048)
			(stroke
				(width 0.1)
				(type default)
			)
			(layer "F.Fab")
		)
		(fp_line
			(start 0.120396 0.2794)
			(end -0.12065 0.2794)
			(stroke
				(width 0.1)
				(type default)
			)
			(layer "F.Fab")
		)
		(fp_line
			(start -0.12065 -0.2794)
			(end 0.12065 -0.2794)
			(stroke
				(width 0.1)
				(type default)
			)
			(layer "F.Fab")
		)
		(fp_line
			(start 0.12065 -0.2794)
			(end 0.12065 -0.3048)
			(stroke
				(width 0.1)
				(type default)
			)
			(layer "F.Fab")
		)
		(fp_line
			(start 0.12065 -0.3048)
			(end 0.67945 -0.3048)
			(stroke
				(width 0.1)
				(type default)
			)
			(layer "F.Fab")
		)
		(fp_line
			(start 0.67945 -0.3048)
			(end 0.67945 0.3048)
			(stroke
				(width 0.1)
				(type default)
			)
			(layer "F.Fab")
		)
		(fp_line
			(start -0.67945 -0.305054)
			(end -0.12065 -0.305054)
			(stroke
				(width 0.1)
				(type default)
			)
			(layer "F.Fab")
		)
		(fp_line
			(start -0.12065 -0.305054)
			(end -0.12065 -0.2794)
			(stroke
				(width 0.1)
				(type default)
			)
			(layer "F.Fab")
		)
		(pad "1" smd circle
			(at -0.40005 0 270)
			(size 0 0)
			(layers "F.Cu" "F.Mask" "F.Paste")
			(net "SMB_PEX2_R_SDA")
		)
		(pad "2" smd circle
			(at 0.40005 0 270)
			(size 0 0)
			(layers "F.Cu" "F.Mask" "F.Paste")
			(net "SMB_PEX2_SDA")
		)
	)
	(footprint ""
		(layer "F.Cu")
		(at 88.475566 -122.931682 -90)
		(property "Reference" "PD54"
			(at 3.497072 2.172208 90)
			(unlocked yes)
			(layer "F.SilkS")
			(effects
				(font
					(size 0.7874 0.5842)
					(thickness 0.1524)
				)
				(justify left)
			)
		)
		(property "Value" ""
			(at 0 0 270)
			(layer "F.Fab")
			(effects
				(font
					(size 1.27 1.27)
				)
			)
		)
		(duplicate_pad_numbers_are_jumpers no)
		(fp_line
			(start -3.400044 1.459992)
			(end -3.400044 -1.459992)
			(stroke
				(width 0.1524)
				(type default)
			)
			(layer "F.SilkS")
		)
		(fp_line
			(start 4.107942 1.459992)
			(end -3.400044 1.459992)
			(stroke
				(width 0.1524)
				(type default)
			)
			(layer "F.SilkS")
		)
		(fp_line
			(start -3.400044 -1.459992)
			(end 4.107942 -1.459992)
			(stroke
				(width 0.1524)
				(type default)
			)
			(layer "F.SilkS")
		)
		(fp_line
			(start 4.107942 -1.459992)
			(end 4.107942 1.459992)
			(stroke
				(width 0.1524)
				(type default)
			)
			(layer "F.SilkS")
		)
		(fp_rect
			(start 4.107942 1.459992)
			(end 3.308096 -1.459992)
			(stroke
				(width 0)
				(type default)
			)
			(fill yes)
			(layer "F.SilkS")
		)
		(fp_line
			(start -2.29997 1.459992)
			(end -2.29997 -1.459992)
			(stroke
				(width 0.1)
				(type default)
			)
			(layer "F.Fab")
		)
		(fp_line
			(start 2.29997 1.459992)
			(end -2.29997 1.459992)
			(stroke
				(width 0.1)
				(type default)
			)
			(layer "F.Fab")
		)
		(fp_line
			(start -2.29997 -1.459992)
			(end 2.29997 -1.459992)
			(stroke
				(width 0.1)
				(type default)
			)
			(layer "F.Fab")
		)
		(fp_line
			(start 2.29997 -1.459992)
			(end 2.29997 1.459992)
			(stroke
				(width 0.1)
				(type default)
			)
			(layer "F.Fab")
		)
		(fp_text user "-"
			(at 5.06222 2.129028 90)
			(unlocked yes)
			(layer "F.SilkS")
			(effects
				(font
					(size 1.905 1.4224)
					(thickness 0.1524)
				)
				(justify left)
			)
		)
		(fp_text user "+"
			(at -4.7752 -0.12065 270)
			(unlocked yes)
			(layer "F.SilkS")
			(effects
				(font
					(size 1.905 1.4224)
					(thickness 0.1524)
				)
				(justify left)
			)
		)
		(fp_text user "-"
			(at 5.4102 0.29845 90)
			(unlocked yes)
			(layer "F.Fab")
			(effects
				(font
					(size 1.905 1.4224)
					(thickness 0.1524)
				)
				(justify left)
			)
		)
		(fp_text user "+"
			(at -4.7752 -0.12065 270)
			(unlocked yes)
			(layer "F.Fab")
			(effects
				(font
					(size 1.905 1.4224)
					(thickness 0.1524)
				)
				(justify left)
			)
		)
		(pad "A" smd rect
			(at -1.999996 0)
			(size 1.7018 2.5146)
			(layers "F.Cu" "F.Mask" "F.Paste")
			(net "GND")
		)
		(pad "C" smd rect
			(at 1.999996 0)
			(size 1.7018 2.5146)
			(layers "F.Cu" "F.Mask" "F.Paste")
			(net "P3V3_NIC1")
		)
	)
	(footprint ""
		(layer "F.Cu")
		(at 452.56704 -57.332626)
		(property "Reference" "R6826"
			(at 0 0 0)
			(layer "F.SilkS")
			(hide yes)
			(effects
				(font
					(size 1.27 1.27)
				)
			)
		)
		(property "Value" ""
			(at 0 0 0)
			(layer "F.Fab")
			(effects
				(font
					(size 1.27 1.27)
				)
			)
		)
		(duplicate_pad_numbers_are_jumpers no)
		(fp_line
			(start -0.7874 -0.4064)
			(end 0.7874 -0.4064)
			(stroke
				(width 0.1524)
				(type default)
			)
			(layer "F.SilkS")
		)
		(fp_line
			(start -0.7874 0.4064)
			(end -0.7874 -0.4064)
			(stroke
				(width 0.1524)
				(type default)
			)
			(layer "F.SilkS")
		)
		(fp_line
			(start 0.7874 -0.4064)
			(end 0.7874 0.4064)
			(stroke
				(width 0.1524)
				(type default)
			)
			(layer "F.SilkS")
		)
		(fp_line
			(start 0.7874 0.4064)
			(end -0.7874 0.4064)
			(stroke
				(width 0.1524)
				(type default)
			)
			(layer "F.SilkS")
		)
		(fp_line
			(start -0.67945 -0.305054)
			(end -0.12065 -0.305054)
			(stroke
				(width 0.1)
				(type default)
			)
			(layer "F.Fab")
		)
		(fp_line
			(start -0.67945 0.3048)
			(end -0.67945 -0.305054)
			(stroke
				(width 0.1)
				(type default)
			)
			(layer "F.Fab")
		)
		(fp_line
			(start -0.12065 -0.305054)
			(end -0.12065 -0.2794)
			(stroke
				(width 0.1)
				(type default)
			)
			(layer "F.Fab")
		)
		(fp_line
			(start -0.12065 -0.2794)
			(end 0.12065 -0.2794)
			(stroke
				(width 0.1)
				(type default)
			)
			(layer "F.Fab")
		)
		(fp_line
			(start -0.12065 0.2794)
			(end -0.12065 0.3048)
			(stroke
				(width 0.1)
				(type default)
			)
			(layer "F.Fab")
		)
		(fp_line
			(start -0.12065 0.3048)
			(end -0.67945 0.3048)
			(stroke
				(width 0.1)
				(type default)
			)
			(layer "F.Fab")
		)
		(fp_line
			(start 0.120396 0.2794)
			(end -0.12065 0.2794)
			(stroke
				(width 0.1)
				(type default)
			)
			(layer "F.Fab")
		)
		(fp_line
			(start 0.120396 0.3048)
			(end 0.120396 0.2794)
			(stroke
				(width 0.1)
				(type default)
			)
			(layer "F.Fab")
		)
		(fp_line
			(start 0.12065 -0.3048)
			(end 0.67945 -0.3048)
			(stroke
				(width 0.1)
				(type default)
			)
			(layer "F.Fab")
		)
		(fp_line
			(start 0.12065 -0.2794)
			(end 0.12065 -0.3048)
			(stroke
				(width 0.1)
				(type default)
			)
			(layer "F.Fab")
		)
		(fp_line
			(start 0.67945 -0.3048)
			(end 0.67945 0.3048)
			(stroke
				(width 0.1)
				(type default)
			)
			(layer "F.Fab")
		)
		(fp_line
			(start 0.67945 0.3048)
			(end 0.120396 0.3048)
			(stroke
				(width 0.1)
				(type default)
			)
			(layer "F.Fab")
		)
		(pad "1" smd circle
			(at -0.40005 0)
			(size 0 0)
			(layers "F.Cu" "F.Mask" "F.Paste")
			(net "SSD15_PWR_EN_R")
		)
		(pad "2" smd circle
			(at 0.40005 0)
			(size 0 0)
			(layers "F.Cu" "F.Mask" "F.Paste")
			(net "GND")
		)
	)
)
